# ZAIUS-LV_CARD-EVT1-X00-BOM-X01_20160825.xls — DEPOP (bom)
| FOXCONN TECHNOLOGY GROUP |  |  |  |  |  |  |  |  |  |  |  |  |
| BILL OF MATERIAL |  |  |  |  |  |  |  |  |  |  |  |  |
| REV OF  BOM | X01 | CUSTOMER | DELL |  | CUSTOMER P/N |  | PRODUCT CODE |  | PWA  REV | X00 | DATE | 42608 |
| Sourcing (Single/Sole/Multi) | Critical Commodity (Y or N) | Component Class (1, 2, other) | Dell PSL (Y or N) | Item Number | Foxconn P/N | Dell P/N | Part Description | Manufacturer  Full Name | Manufacturer  Part Number | Qty | RoHS Status | Location |
|  | N | ND | N | 1 | 610107A00-017-G | - | RES,0 Ohm,+/-5%,1/16W,G,SMD0402 | KOA SPEER ELECTRONICS, INC. | RK73Z1ETTP | 10 | N | R1,R3,R4,R5,R7,R8,R9,R10,R11,R12 |
